# BASEBOARD_FAB2 (Tioga Pass) — schematic netlist excerpt (pin names and nets, part order shuffled) for the footprints in the layout excerpt that follows; sources: Cadence DE-HDL packaged netlist, KiCad conversion of Wiwynn_Tioga_Pass_MB.brd

J8G1  SCONN200_H68296001  CONN  pkg SM  page 108
  IO1  = P12V
  IO2  = P12V
  IO3  = P12V
  IO4  = P12V
  IO5  = P12V
  IO6  = P12V
  IO7  = P12V
  IO8  = P12V
  IO9  = P12V
  IO10  = P12V
  IO11  = P12V
  IO12  = P12V
  IO13  = GND
  IO14  = GND
  IO15  = SMB_SLOTX24_STBY_LVC3_SDA_R2
  IO16  = IRQ_OOB_MGMT_RISER_ALERT_N
  IO17  = SMB_SLOTX24_STBY_LVC3_SCL_R2
  IO18  = FM_SLT_CFG1
  IO19  = FM_SLT_CFG0
  IO20  = FM_PWRBRK_SLOT_N
  IO21  = P3V3
  IO22  = P3V3
  IO23  = P3V3
  IO24  = P3V3
  IO25  = P3V3_STBY
  IO26  = GND
  IO27  = PU_PCH_TLS_ENABLE_STRAP
  IO28  = FM_PE_SLOTX24_WAKE_N
  IO29  = RST_PCIE_RISER1_PERST_R_N
  IO30  = SMB_HOST_STBY_LVC3_SDA_R5
  IO31  = GND
  IO32  = SMB_HOST_STBY_LVC3_SCL_R5
  IO33  = CLK_100M_PCH_SLOTX24_S5_DP
  IO34  = GND
  IO35  = CLK_100M_PCH_SLOTX24_S5_DN
  IO36  = CLK_100M_PCH_SLOTX24_S4_DP
  IO37  = GND
  IO38  = CLK_100M_PCH_SLOTX24_S4_DN
  IO39  = CLK_100M_PCH_SLOTX24_S0_DP
  IO40  = GND
  IO41  = CLK_100M_PCH_SLOTX24_S0_DN
  IO42  = CLK_100M_PCH_SLOTX24_S1_DP
  IO43  = GND
  IO44  = CLK_100M_PCH_SLOTX24_S1_DN
  IO45  = CLK_100M_PCH_SLOTX24_S3_DP
  IO46  = GND
  IO47  = CLK_100M_PCH_SLOTX24_S3_DN
  IO48  = CLK_100M_PCH_SLOTX24_S2_DP
  IO49  = GND
  IO50  = CLK_100M_PCH_SLOTX24_S2_DN
  IO51  = P3E_CPU0_PE1_PCH_CON_TXN<15>
  IO52  = GND
  IO53  = P3E_CPU0_PE1_PCH_CON_TXP<15>
  IO54  = P3E_CPU0_PE1_PCH_CON_RXN<15>
  IO55  = GND
  IO56  = P3E_CPU0_PE1_PCH_CON_RXP<15>
  IO57  = P3E_CPU0_PE1_PCH_CON_TXP<14>
  IO58  = GND
  IO59  = P3E_CPU0_PE1_PCH_CON_TXN<14>
  IO60  = P3E_CPU0_PE1_PCH_CON_RXN<14>
  IO61  = GND
  IO62  = P3E_CPU0_PE1_PCH_CON_RXP<14>
  IO63  = TP_SLOTX24_RSVD63
  IO64  = GND
  IO65  = GND
  IO66  = TP_SLOTX24_RSVD66
  IO67  = P3E_CPU0_PE1_PCH_CON_TXN<13>
  IO68  = GND
  IO69  = P3E_CPU0_PE1_PCH_CON_TXP<13>
  IO70  = P3E_CPU0_PE1_PCH_CON_RXN<13>
  IO71  = GND
  IO72  = P3E_CPU0_PE1_PCH_CON_RXP<13>
  IO73  = P3E_CPU0_PE1_PCH_CON_TXN<12>
  IO74  = GND
  IO75  = P3E_CPU0_PE1_PCH_CON_TXP<12>
  IO76  = P3E_CPU0_PE1_PCH_CON_RXN<12>
  IO77  = GND
  IO78  = P3E_CPU0_PE1_PCH_CON_RXP<12>
  IO79  = P3E_CPU0_PE1_PCH_CON_TXN<11>
  IO80  = GND
  IO81  = P3E_CPU0_PE1_PCH_CON_TXP<11>
  IO82  = P3E_CPU0_PE1_PCH_CON_RXN<11>
  IO83  = GND
  IO84  = P3E_CPU0_PE1_PCH_CON_RXP<11>
  IO85  = P3E_CPU0_PE1_PCH_CON_TXN<10>
  IO86  = GND
  IO87  = P3E_CPU0_PE1_PCH_CON_TXP<10>
  IO88  = P3E_CPU0_PE1_PCH_CON_RXN<10>
  IO89  = GND
  IO90  = P3E_CPU0_PE1_PCH_CON_RXP<10>
  IO91  = P3E_CPU0_PE1_PCH_CON_TXN<9>
  IO92  = GND
  IO93  = P3E_CPU0_PE1_PCH_CON_TXP<9>
  IO94  = P3E_CPU0_PE1_PCH_CON_RXN<9>
  IO95  = GND
  IO96  = P3E_CPU0_PE1_PCH_CON_RXP<9>
  IO97  = P3E_CPU0_PE1_PCH_CON_TXN<8>
  IO98  = GND
  IO99  = P3E_CPU0_PE1_PCH_CON_TXP<8>
  IO100  = P3E_CPU0_PE1_PCH_CON_RXN<8>
  IO101  = GND
  IO102  = P3E_CPU0_PE1_PCH_CON_RXP<8>
  IO103  = P3E_CPU0_PE1_SS_C_TXP<7>
  IO104  = GND
  IO105  = P3E_CPU0_PE1_SS_C_TXN<7>
  IO106  = P3E_CPU0_PE1_SS_R_RXN<7>
  IO107  = GND
  IO108  = P3E_CPU0_PE1_SS_R_RXP<7>
  IO109  = P3E_CPU0_PE1_SS_C_TXN<6>
  IO110  = GND
  IO111  = P3E_CPU0_PE1_SS_C_TXP<6>
  IO112  = P3E_CPU0_PE1_SS_R_RXN<6>
  IO113  = GND
  IO114  = P3E_CPU0_PE1_SS_R_RXP<6>
  IO115  = P3E_CPU0_PE1_SS_C_TXN<5>
  IO116  = GND
  IO117  = P3E_CPU0_PE1_SS_C_TXP<5>
  IO118  = P3E_CPU0_PE1_SS_R_RXN<5>
  IO119  = GND
  IO120  = P3E_CPU0_PE1_SS_R_RXP<5>
  IO121  = P3E_CPU0_PE1_SS_C_TXN<4>
  IO122  = GND
  IO123  = P3E_CPU0_PE1_SS_C_TXP<4>
  IO124  = P3E_CPU0_PE1_SS_R_RXN<4>
  IO125  = GND
  IO126  = P3E_CPU0_PE1_SS_R_RXP<4>
  IO127  = P3E_CPU0_PE1_SS_C_TXN<3>
  IO128  = GND
  IO129  = P3E_CPU0_PE1_SS_C_TXP<3>
  IO130  = P3E_CPU0_PE1_SS_R_RXN<3>
  IO131  = GND
  IO132  = P3E_CPU0_PE1_SS_R_RXP<3>
  IO133  = P3E_CPU0_PE1_SS_C_TXN<2>
  IO134  = GND
  IO135  = P3E_CPU0_PE1_SS_C_TXP<2>
  IO136  = P3E_CPU0_PE1_SS_R_RXN<2>
  IO137  = GND
  IO138  = P3E_CPU0_PE1_SS_R_RXP<2>
  IO139  = P3E_CPU0_PE1_SS_C_TXN<1>
  IO140  = GND
  IO141  = P3E_CPU0_PE1_SS_C_TXP<1>
  IO142  = P3E_CPU0_PE1_SS_R_RXN<1>
  IO143  = GND
  IO144  = P3E_CPU0_PE1_SS_R_RXP<1>
  IO145  = P3E_CPU0_PE1_SS_C_TXN<0>
  IO146  = GND
  IO147  = P3E_CPU0_PE1_SS_C_TXP<0>
  IO148  = P3E_CPU0_PE1_SS_R_RXN<0>
  IO149  = GND
  IO150  = P3E_CPU0_PE1_SS_R_RXP<0>
  IO151  = P3E_CPU0_PE2_SS_C_TXN<0>
  IO152  = GND
  IO153  = P3E_CPU0_PE2_SS_C_TXP<0>
  IO154  = P3E_CPU0_PE2_SS_RXN<0>
  IO155  = GND
  IO156  = P3E_CPU0_PE2_SS_RXP<0>
  IO157  = P3E_CPU0_PE2_SS_C_TXP<1>
  IO158  = GND
  IO159  = P3E_CPU0_PE2_SS_C_TXN<1>
  IO160  = P3E_CPU0_PE2_SS_RXN<1>
  IO161  = GND
  IO162  = P3E_CPU0_PE2_SS_RXP<1>
  IO163  = P3E_CPU0_PE2_SS_C_TXN<2>
  IO164  = GND
  IO165  = P3E_CPU0_PE2_SS_C_TXP<2>
  IO166  = P3E_CPU0_PE2_SS_RXN<2>
  IO167  = GND
  IO168  = P3E_CPU0_PE2_SS_RXP<2>
  IO169  = P3E_CPU0_PE2_SS_C_TXN<3>
  IO170  = GND
  IO171  = P3E_CPU0_PE2_SS_C_TXP<3>
  IO172  = P3E_CPU0_PE2_SS_RXN<3>
  IO173  = GND
  IO174  = P3E_CPU0_PE2_SS_RXP<3>
  IO175  = P3E_CPU0_PE2_SS_C_TXN<4>
  IO176  = GND
  IO177  = P3E_CPU0_PE2_SS_C_TXP<4>
  IO178  = P3E_CPU0_PE2_SS_RXN<4>
  IO179  = GND
  IO180  = P3E_CPU0_PE2_SS_RXP<4>
  IO181  = P3E_CPU0_PE2_SS_C_TXN<5>
  IO182  = GND
  IO183  = P3E_CPU0_PE2_SS_C_TXP<5>
  IO184  = P3E_CPU0_PE2_SS_RXN<5>
  IO185  = GND
  IO186  = P3E_CPU0_PE2_SS_RXP<5>
  IO187  = P3E_CPU0_PE2_SS_C_TXN<6>
  IO188  = GND
  IO189  = P3E_CPU0_PE2_SS_C_TXP<6>
  IO190  = P3E_CPU0_PE2_SS_RXP<6>
  IO191  = GND
  IO192  = P3E_CPU0_PE2_SS_RXN<6>
  IO193  = P3E_CPU0_PE2_SS_C_TXN<7>
  IO194  = GND
  IO195  = P3E_CPU0_PE2_SS_C_TXP<7>
  IO196  = P3E_CPU0_PE2_SS_RXN<7>
  IO197  = GND
  IO198  = P3E_CPU0_PE2_SS_RXP<7>
  IO199  = FM_PRSNT_2_6_N
  IO200  = GND
  MH1  = GND
  MH2  = GND

(kicad_pcb
	(version 20260206)
	(generator "pcbnew")
	(generator_version "10.0")
	(general
		(thickness 1.6)
		(legacy_teardrops no)
	)
	(paper "A4")
	(title_block
		(title "Wiwynn_Tioga_Pass_MB.brd")
		(comment 1 "Tioga Pass / footprint 949 of 4770 (J8G1), pads 140-185 of 204")
	)
	(layers
		(0 "F.Cu" signal "TOP")
		(4 "In1.Cu" signal "L2GND")
		(6 "In2.Cu" signal "L3")
		(8 "In3.Cu" signal "L4GND")
		(10 "In4.Cu" signal "L5")
		(12 "In5.Cu" signal "L6GND")
		(14 "In6.Cu" signal "L7VCC")
		(16 "In7.Cu" signal "L8VCC")
		(18 "In8.Cu" signal "L9GND")
		(20 "In9.Cu" signal "L10")
		(22 "In10.Cu" signal "L11GND")
		(24 "In11.Cu" signal "L12")
		(26 "In12.Cu" signal "L13GND")
		(2 "B.Cu" signal "BOTTOM")
		(9 "F.Adhes" user "F.Adhesive")
		(11 "B.Adhes" user "B.Adhesive")
		(13 "F.Paste" user "Package Geometry/Pastemask Top")
		(15 "B.Paste" user "Package Geometry/Pastemask Bottom")
		(5 "F.SilkS" user "Ref Des/Silkscreen Top")
		(7 "B.SilkS" user "Ref Des/Silkscreen Bottom")
		(1 "F.Mask" user "Board Geometry/Soldermask Top")
		(3 "B.Mask" user "Board Geometry/Soldermask Bottom")
		(17 "Dwgs.User" user "User.Drawings")
		(19 "Cmts.User" user "User.Comments")
		(21 "Eco1.User" user "User.Eco1")
		(23 "Eco2.User" user "User.Eco2")
		(25 "Edge.Cuts" user "Board Geometry/Outline")
		(27 "Margin" user)
		(31 "F.CrtYd" user "Package Geometry/Place Bound Top")
		(29 "B.CrtYd" user "Package Geometry/Place Bound Bottom")
		(35 "F.Fab" user "Ref Des/Assembly Top")
		(33 "B.Fab" user "Ref Des/Assembly Bottom")
	)
	(footprint ""
		(layer "F.Cu")
		(at 474.080078 -7.789672 -90)
		(property "Reference" "J8G1"
			(at -3.126486 25.39111 0)
			(unlocked yes)
			(layer "F.SilkS")
			(effects
				(font
					(size 0.7874 0.5842)
					(thickness 0.1524)
				)
				(justify left)
			)
		)
		(property "Value" ""
			(at 0 0 270)
			(layer "F.Fab")
			(effects
				(font
					(size 1.27 1.27)
				)
			)
		)
		(duplicate_pad_numbers_are_jumpers no)
		(pad "138" smd rect
			(at 3.4036 57.606692 270)
			(size 1.1938 0.508)
			(layers "F.Cu" "F.Mask" "F.Paste")
			(net "P3E_CPU0_PE1_SS_R_RXP<2>")
		)
		(pad "139" smd rect
			(at 0 58.406792 270)
			(size 1.1938 0.508)
			(layers "F.Cu" "F.Mask" "F.Paste")
			(net "P3E_CPU0_PE1_SS_C_TXN<1>")
		)
		(pad "140" smd rect
			(at 3.4036 58.406792 270)
			(size 1.1938 0.508)
			(layers "F.Cu" "F.Mask" "F.Paste")
			(net "GND")
		)
		(pad "141" smd rect
			(at 0 59.206892 270)
			(size 1.1938 0.508)
			(layers "F.Cu" "F.Mask" "F.Paste")
			(net "P3E_CPU0_PE1_SS_C_TXP<1>")
		)
		(pad "142" smd rect
			(at 3.4036 59.206892 270)
			(size 1.1938 0.508)
			(layers "F.Cu" "F.Mask" "F.Paste")
			(net "P3E_CPU0_PE1_SS_R_RXN<1>")
		)
		(pad "143" smd rect
			(at 0 60.006992 270)
			(size 1.1938 0.508)
			(layers "F.Cu" "F.Mask" "F.Paste")
			(net "GND")
		)
		(pad "144" smd rect
			(at 3.4036 60.006992 270)
			(size 1.1938 0.508)
			(layers "F.Cu" "F.Mask" "F.Paste")
			(net "P3E_CPU0_PE1_SS_R_RXP<1>")
		)
		(pad "145" smd rect
			(at 0 60.807092 270)
			(size 1.1938 0.508)
			(layers "F.Cu" "F.Mask" "F.Paste")
			(net "P3E_CPU0_PE1_SS_C_TXN<0>")
		)
		(pad "146" smd rect
			(at 3.4036 60.807092 270)
			(size 1.1938 0.508)
			(layers "F.Cu" "F.Mask" "F.Paste")
			(net "GND")
		)
		(pad "147" smd rect
			(at 0 61.607192 270)
			(size 1.1938 0.508)
			(layers "F.Cu" "F.Mask" "F.Paste")
			(net "P3E_CPU0_PE1_SS_C_TXP<0>")
		)
		(pad "148" smd rect
			(at 3.4036 61.607192 270)
			(size 1.1938 0.508)
			(layers "F.Cu" "F.Mask" "F.Paste")
			(net "P3E_CPU0_PE1_SS_R_RXN<0>")
		)
		(pad "149" smd rect
			(at 0 62.407292 270)
			(size 1.1938 0.508)
			(layers "F.Cu" "F.Mask" "F.Paste")
			(net "GND")
		)
		(pad "150" smd rect
			(at 3.4036 62.407292 270)
			(size 1.1938 0.508)
			(layers "F.Cu" "F.Mask" "F.Paste")
			(net "P3E_CPU0_PE1_SS_R_RXP<0>")
		)
		(pad "151" smd rect
			(at 0 63.207392 270)
			(size 1.1938 0.508)
			(layers "F.Cu" "F.Mask" "F.Paste")
			(net "P3E_CPU0_PE2_SS_C_TXN<0>")
		)
		(pad "152" smd rect
			(at 3.4036 63.207392 270)
			(size 1.1938 0.508)
			(layers "F.Cu" "F.Mask" "F.Paste")
			(net "GND")
		)
		(pad "153" smd rect
			(at 0 64.007492 270)
			(size 1.1938 0.508)
			(layers "F.Cu" "F.Mask" "F.Paste")
			(net "P3E_CPU0_PE2_SS_C_TXP<0>")
		)
		(pad "154" smd rect
			(at 3.4036 64.007492 270)
			(size 1.1938 0.508)
			(layers "F.Cu" "F.Mask" "F.Paste")
			(net "P3E_CPU0_PE2_SS_RXN<0>")
		)
		(pad "155" smd rect
			(at 0 64.807592 270)
			(size 1.1938 0.508)
			(layers "F.Cu" "F.Mask" "F.Paste")
			(net "GND")
		)
		(pad "156" smd rect
			(at 3.4036 64.807592 270)
			(size 1.1938 0.508)
			(layers "F.Cu" "F.Mask" "F.Paste")
			(net "P3E_CPU0_PE2_SS_RXP<0>")
		)
		(pad "157" smd rect
			(at 0 65.607692 270)
			(size 1.1938 0.508)
			(layers "F.Cu" "F.Mask" "F.Paste")
			(net "P3E_CPU0_PE2_SS_C_TXP<1>")
		)
		(pad "158" smd rect
			(at 3.4036 65.607692 270)
			(size 1.1938 0.508)
			(layers "F.Cu" "F.Mask" "F.Paste")
			(net "GND")
		)
		(pad "159" smd rect
			(at 0 66.407792 270)
			(size 1.1938 0.508)
			(layers "F.Cu" "F.Mask" "F.Paste")
			(net "P3E_CPU0_PE2_SS_C_TXN<1>")
		)
		(pad "160" smd rect
			(at 3.4036 66.407792 270)
			(size 1.1938 0.508)
			(layers "F.Cu" "F.Mask" "F.Paste")
			(net "P3E_CPU0_PE2_SS_RXN<1>")
		)
		(pad "161" smd rect
			(at 0 67.207892 270)
			(size 1.1938 0.508)
			(layers "F.Cu" "F.Mask" "F.Paste")
			(net "GND")
		)
		(pad "162" smd rect
			(at 3.4036 67.207892 270)
			(size 1.1938 0.508)
			(layers "F.Cu" "F.Mask" "F.Paste")
			(net "P3E_CPU0_PE2_SS_RXP<1>")
		)
		(pad "163" smd rect
			(at 0 68.007992 270)
			(size 1.1938 0.508)
			(layers "F.Cu" "F.Mask" "F.Paste")
			(net "P3E_CPU0_PE2_SS_C_TXN<2>")
		)
		(pad "164" smd rect
			(at 3.4036 68.007992 270)
			(size 1.1938 0.508)
			(layers "F.Cu" "F.Mask" "F.Paste")
			(net "GND")
		)
		(pad "165" smd rect
			(at 0 68.808092 270)
			(size 1.1938 0.508)
			(layers "F.Cu" "F.Mask" "F.Paste")
			(net "P3E_CPU0_PE2_SS_C_TXP<2>")
		)
		(pad "166" smd rect
			(at 3.4036 68.808092 270)
			(size 1.1938 0.508)
			(layers "F.Cu" "F.Mask" "F.Paste")
			(net "P3E_CPU0_PE2_SS_RXN<2>")
		)
		(pad "167" smd rect
			(at 0 69.608192 270)
			(size 1.1938 0.508)
			(layers "F.Cu" "F.Mask" "F.Paste")
			(net "GND")
		)
		(pad "168" smd rect
			(at 3.4036 69.608192 270)
			(size 1.1938 0.508)
			(layers "F.Cu" "F.Mask" "F.Paste")
			(net "P3E_CPU0_PE2_SS_RXP<2>")
		)
		(pad "169" smd rect
			(at 0 70.408292 270)
			(size 1.1938 0.508)
			(layers "F.Cu" "F.Mask" "F.Paste")
			(net "P3E_CPU0_PE2_SS_C_TXN<3>")
		)
		(pad "170" smd rect
			(at 3.4036 70.408292 270)
			(size 1.1938 0.508)
			(layers "F.Cu" "F.Mask" "F.Paste")
			(net "GND")
		)
		(pad "171" smd rect
			(at 0 71.208392 270)
			(size 1.1938 0.508)
			(layers "F.Cu" "F.Mask" "F.Paste")
			(net "P3E_CPU0_PE2_SS_C_TXP<3>")
		)
		(pad "172" smd rect
			(at 3.4036 71.208392 270)
			(size 1.1938 0.508)
			(layers "F.Cu" "F.Mask" "F.Paste")
			(net "P3E_CPU0_PE2_SS_RXN<3>")
		)
		(pad "173" smd rect
			(at 0 72.008492 270)
			(size 1.1938 0.508)
			(layers "F.Cu" "F.Mask" "F.Paste")
			(net "GND")
		)
		(pad "174" smd rect
			(at 3.4036 72.008492 270)
			(size 1.1938 0.508)
			(layers "F.Cu" "F.Mask" "F.Paste")
			(net "P3E_CPU0_PE2_SS_RXP<3>")
		)
		(pad "175" smd rect
			(at 0 72.808592 270)
			(size 1.1938 0.508)
			(layers "F.Cu" "F.Mask" "F.Paste")
			(net "P3E_CPU0_PE2_SS_C_TXN<4>")
		)
		(pad "176" smd rect
			(at 3.4036 72.808592 270)
			(size 1.1938 0.508)
			(layers "F.Cu" "F.Mask" "F.Paste")
			(net "GND")
		)
		(pad "177" smd rect
			(at 0 73.608692 270)
			(size 1.1938 0.508)
			(layers "F.Cu" "F.Mask" "F.Paste")
			(net "P3E_CPU0_PE2_SS_C_TXP<4>")
		)
		(pad "178" smd rect
			(at 3.4036 73.608692 270)
			(size 1.1938 0.508)
			(layers "F.Cu" "F.Mask" "F.Paste")
			(net "P3E_CPU0_PE2_SS_RXN<4>")
		)
		(pad "179" smd rect
			(at 0 74.408792 270)
			(size 1.1938 0.508)
			(layers "F.Cu" "F.Mask" "F.Paste")
			(net "GND")
		)
		(pad "180" smd rect
			(at 3.4036 74.408792 270)
			(size 1.1938 0.508)
			(layers "F.Cu" "F.Mask" "F.Paste")
			(net "P3E_CPU0_PE2_SS_RXP<4>")
		)
		(pad "181" smd rect
			(at 0 75.208892 270)
			(size 1.1938 0.508)
			(layers "F.Cu" "F.Mask" "F.Paste")
			(net "P3E_CPU0_PE2_SS_C_TXN<5>")
		)
		(pad "182" smd rect
			(at 3.4036 75.208892 270)
			(size 1.1938 0.508)
			(layers "F.Cu" "F.Mask" "F.Paste")
			(net "GND")
		)
		(pad "183" smd rect
			(at 0 76.008992 270)
			(size 1.1938 0.508)
			(layers "F.Cu" "F.Mask" "F.Paste")
			(net "P3E_CPU0_PE2_SS_C_TXP<5>")
		)
	)
)
